(kicad_pcb
	(version 20260206)
	(generator "pcbnew")
	(generator_version "10.0")
	(general
		(thickness 1.6)
		(legacy_teardrops no)
	)
	(paper "A4")
	(title_block
		(title "04192023_DAF0TMB3IC0_F0TG_MB_C_brd_V02_OCP.brd")
		(comment 1 "Grand Teton / footprints 1339-1341 of 8354")
	)
	(layers
		(0 "F.Cu" signal "TOP")
		(4 "In1.Cu" signal "GND")
		(6 "In2.Cu" signal "IN1")
		(8 "In3.Cu" signal "GND1")
		(10 "In4.Cu" signal "IN2")
		(12 "In5.Cu" signal "GND2")
		(14 "In6.Cu" signal "IN3")
		(16 "In7.Cu" signal "GND3")
		(18 "In8.Cu" signal "VCC")
		(20 "In9.Cu" signal "VCC1")
		(22 "In10.Cu" signal "GND4")
		(24 "In11.Cu" signal "IN4")
		(26 "In12.Cu" signal "GND5")
		(28 "In13.Cu" signal "IN5")
		(30 "In14.Cu" signal "GND6")
		(32 "In15.Cu" signal "IN6")
		(34 "In16.Cu" signal "GND7")
		(2 "B.Cu" signal "BOTTOM")
		(9 "F.Adhes" user "F.Adhesive")
		(11 "B.Adhes" user "B.Adhesive")
		(13 "F.Paste" user "Package Geometry/Pastemask Top")
		(15 "B.Paste" user "Package Geometry/Pastemask Bottom")
		(5 "F.SilkS" user "Ref Des/Silkscreen Top")
		(7 "B.SilkS" user "Ref Des/Silkscreen Bottom")
		(1 "F.Mask" user "Board Geometry/Soldermask Top")
		(3 "B.Mask" user "Board Geometry/Soldermask Bottom")
		(17 "Dwgs.User" user "User.Drawings")
		(19 "Cmts.User" user "User.Comments")
		(21 "Eco1.User" user "User.Eco1")
		(23 "Eco2.User" user "User.Eco2")
		(25 "Edge.Cuts" user "Board Geometry/Outline")
		(27 "Margin" user)
		(31 "F.CrtYd" user "Package Geometry/Place Bound Top")
		(29 "B.CrtYd" user "Package Geometry/Place Bound Bottom")
		(35 "F.Fab" user "Ref Des/Assembly Top")
		(33 "B.Fab" user "Ref Des/Assembly Bottom")
	)
	(footprint ""
		(layer "F.Cu")
		(at 17.305782 -404.341584 90)
		(property "Reference" "R660"
			(at 0 0 90)
			(layer "F.SilkS")
			(hide yes)
			(effects
				(font
					(size 1.27 1.27)
				)
			)
		)
		(property "Value" ""
			(at 0 0 90)
			(layer "F.Fab")
			(effects
				(font
					(size 1.27 1.27)
				)
			)
		)
		(duplicate_pad_numbers_are_jumpers no)
		(fp_line
			(start 0.7874 -0.4064)
			(end 0.7874 0.4064)
			(stroke
				(width 0.1524)
				(type default)
			)
			(layer "F.SilkS")
		)
		(fp_line
			(start -0.7874 -0.4064)
			(end 0.7874 -0.4064)
			(stroke
				(width 0.1524)
				(type default)
			)
			(layer "F.SilkS")
		)
		(fp_line
			(start 0.7874 0.4064)
			(end -0.7874 0.4064)
			(stroke
				(width 0.1524)
				(type default)
			)
			(layer "F.SilkS")
		)
		(fp_line
			(start -0.7874 0.4064)
			(end -0.7874 -0.4064)
			(stroke
				(width 0.1524)
				(type default)
			)
			(layer "F.SilkS")
		)
		(fp_line
			(start -0.12065 -0.305054)
			(end -0.12065 -0.2794)
			(stroke
				(width 0.1)
				(type default)
			)
			(layer "F.Fab")
		)
		(fp_line
			(start -0.67945 -0.305054)
			(end -0.12065 -0.305054)
			(stroke
				(width 0.1)
				(type default)
			)
			(layer "F.Fab")
		)
		(fp_line
			(start 0.67945 -0.3048)
			(end 0.67945 0.3048)
			(stroke
				(width 0.1)
				(type default)
			)
			(layer "F.Fab")
		)
		(fp_line
			(start 0.12065 -0.3048)
			(end 0.67945 -0.3048)
			(stroke
				(width 0.1)
				(type default)
			)
			(layer "F.Fab")
		)
		(fp_line
			(start 0.12065 -0.2794)
			(end 0.12065 -0.3048)
			(stroke
				(width 0.1)
				(type default)
			)
			(layer "F.Fab")
		)
		(fp_line
			(start -0.12065 -0.2794)
			(end 0.12065 -0.2794)
			(stroke
				(width 0.1)
				(type default)
			)
			(layer "F.Fab")
		)
		(fp_line
			(start 0.120396 0.2794)
			(end -0.12065 0.2794)
			(stroke
				(width 0.1)
				(type default)
			)
			(layer "F.Fab")
		)
		(fp_line
			(start -0.12065 0.2794)
			(end -0.12065 0.3048)
			(stroke
				(width 0.1)
				(type default)
			)
			(layer "F.Fab")
		)
		(fp_line
			(start 0.67945 0.3048)
			(end 0.120396 0.3048)
			(stroke
				(width 0.1)
				(type default)
			)
			(layer "F.Fab")
		)
		(fp_line
			(start 0.120396 0.3048)
			(end 0.120396 0.2794)
			(stroke
				(width 0.1)
				(type default)
			)
			(layer "F.Fab")
		)
		(fp_line
			(start -0.12065 0.3048)
			(end -0.67945 0.3048)
			(stroke
				(width 0.1)
				(type default)
			)
			(layer "F.Fab")
		)
		(fp_line
			(start -0.67945 0.3048)
			(end -0.67945 -0.305054)
			(stroke
				(width 0.1)
				(type default)
			)
			(layer "F.Fab")
		)
		(pad "1" smd circle
			(at -0.40005 0 90)
			(size 0 0)
			(layers "F.Cu" "F.Mask" "F.Paste")
			(net "P3V3_AUX")
		)
		(pad "2" smd circle
			(at 0.40005 0 90)
			(size 0 0)
			(layers "F.Cu" "F.Mask" "F.Paste")
			(net "TP_P0V9_RETIMER_CPU1_PMALERT")
		)
	)
	(footprint ""
		(layer "F.Cu")
		(at 265.176 -136.652 180)
		(property "Reference" "R8005"
			(at 0 0 180)
			(layer "F.SilkS")
			(hide yes)
			(effects
				(font
					(size 1.27 1.27)
				)
			)
		)
		(property "Value" ""
			(at 0 0 180)
			(layer "F.Fab")
			(effects
				(font
					(size 1.27 1.27)
				)
			)
		)
		(duplicate_pad_numbers_are_jumpers no)
		(fp_line
			(start 0.7874 0.4064)
			(end -0.7874 0.4064)
			(stroke
				(width 0.1524)
				(type default)
			)
			(layer "F.SilkS")
		)
		(fp_line
			(start 0.7874 -0.4064)
			(end 0.7874 0.4064)
			(stroke
				(width 0.1524)
				(type default)
			)
			(layer "F.SilkS")
		)
		(fp_line
			(start -0.7874 0.4064)
			(end -0.7874 -0.4064)
			(stroke
				(width 0.1524)
				(type default)
			)
			(layer "F.SilkS")
		)
		(fp_line
			(start -0.7874 -0.4064)
			(end 0.7874 -0.4064)
			(stroke
				(width 0.1524)
				(type default)
			)
			(layer "F.SilkS")
		)
		(fp_line
			(start 0.67945 0.3048)
			(end 0.120396 0.3048)
			(stroke
				(width 0.1)
				(type default)
			)
			(layer "F.Fab")
		)
		(fp_line
			(start 0.67945 -0.3048)
			(end 0.67945 0.3048)
			(stroke
				(width 0.1)
				(type default)
			)
			(layer "F.Fab")
		)
		(fp_line
			(start 0.12065 -0.2794)
			(end 0.12065 -0.3048)
			(stroke
				(width 0.1)
				(type default)
			)
			(layer "F.Fab")
		)
		(fp_line
			(start 0.12065 -0.3048)
			(end 0.67945 -0.3048)
			(stroke
				(width 0.1)
				(type default)
			)
			(layer "F.Fab")
		)
		(fp_line
			(start 0.120396 0.3048)
			(end 0.120396 0.2794)
			(stroke
				(width 0.1)
				(type default)
			)
			(layer "F.Fab")
		)
		(fp_line
			(start 0.120396 0.2794)
			(end -0.12065 0.2794)
			(stroke
				(width 0.1)
				(type default)
			)
			(layer "F.Fab")
		)
		(fp_line
			(start -0.12065 0.3048)
			(end -0.67945 0.3048)
			(stroke
				(width 0.1)
				(type default)
			)
			(layer "F.Fab")
		)
		(fp_line
			(start -0.12065 0.2794)
			(end -0.12065 0.3048)
			(stroke
				(width 0.1)
				(type default)
			)
			(layer "F.Fab")
		)
		(fp_line
			(start -0.12065 -0.2794)
			(end 0.12065 -0.2794)
			(stroke
				(width 0.1)
				(type default)
			)
			(layer "F.Fab")
		)
		(fp_line
			(start -0.12065 -0.305054)
			(end -0.12065 -0.2794)
			(stroke
				(width 0.1)
				(type default)
			)
			(layer "F.Fab")
		)
		(fp_line
			(start -0.67945 0.3048)
			(end -0.67945 -0.305054)
			(stroke
				(width 0.1)
				(type default)
			)
			(layer "F.Fab")
		)
		(fp_line
			(start -0.67945 -0.305054)
			(end -0.12065 -0.305054)
			(stroke
				(width 0.1)
				(type default)
			)
			(layer "F.Fab")
		)
		(pad "1" smd circle
			(at -0.40005 0 180)
			(size 0 0)
			(layers "F.Cu" "F.Mask" "F.Paste")
			(net "SPI_CPU0_D3")
		)
		(pad "2" smd circle
			(at 0.40005 0 180)
			(size 0 0)
			(layers "F.Cu" "F.Mask" "F.Paste")
			(net "SPI_CPU0_R1_D3")
		)
	)
	(footprint ""
		(layer "F.Cu")
		(at 324.981062 -402.9202 -90)
		(property "Reference" "R6820"
			(at 0 0 270)
			(layer "F.SilkS")
			(hide yes)
			(effects
				(font
					(size 1.27 1.27)
				)
			)
		)
		(property "Value" ""
			(at 0 0 270)
			(layer "F.Fab")
			(effects
				(font
					(size 1.27 1.27)
				)
			)
		)
		(duplicate_pad_numbers_are_jumpers no)
		(fp_line
			(start -0.32512 0.175006)
			(end -0.32512 -0.175006)
			(stroke
				(width 0.1)
				(type default)
			)
			(layer "F.Fab")
		)
		(fp_line
			(start 0.32512 0.175006)
			(end -0.32512 0.175006)
			(stroke
				(width 0.1)
				(type default)
			)
			(layer "F.Fab")
		)
		(fp_line
			(start -0.32512 -0.175006)
			(end 0.32512 -0.175006)
			(stroke
				(width 0.1)
				(type default)
			)
			(layer "F.Fab")
		)
		(fp_line
			(start 0.32512 -0.175006)
			(end 0.32512 0.175006)
			(stroke
				(width 0.1)
				(type default)
			)
			(layer "F.Fab")
		)
		(pad "1" smd rect
			(at -0.2667 0 270)
			(size 0.3048 0.381)
			(layers "F.Cu" "F.Mask" "F.Paste")
			(net "NCF_A1_CPU0_P0_GND")
		)
		(pad "2" smd rect
			(at 0.2667 0 90)
			(size 0.3048 0.381)
			(layers "F.Cu" "F.Mask" "F.Paste")
			(net "GND")
		)
	)
)
